# T6G (Grand Teton) — schematic netlist excerpt (pin names and nets, part order shuffled) for the footprints in the layout excerpt that follows; sources: Cadence DE-HDL packaged netlist, KiCad conversion of 04192023_DAF0TMB3IC0_F0TG_MB_C_brd_V02_OCP.brd

R1633  Q_RES  0 5% CHIP  pkg 0402LF  page 172 : A = JTAG_TCK_R ; B = JTAG_TCK
PC584_2  Q_CAP  1UF 25V 10% X6S  pkg C0402  page 198 : A = SW_P12V_AUX_PVDDCR_SOC_P0_FLT ; B = GND
PL24  Q_INDUCTOR  100NH/16A IND  pkg SMLF  page 208 : \1\ = SW_P12V_AUX_PVDD11_S3_P0_FLT ; \2\ = P12V_AUX

(kicad_pcb
	(version 20260206)
	(generator "pcbnew")
	(generator_version "10.0")
	(general
		(thickness 1.6)
		(legacy_teardrops no)
	)
	(paper "A4")
	(title_block
		(title "04192023_DAF0TMB3IC0_F0TG_MB_C_brd_V02_OCP.brd")
		(comment 1 "Grand Teton / footprints 2932-2934 of 8354")
	)
	(layers
		(0 "F.Cu" signal "TOP")
		(4 "In1.Cu" signal "GND")
		(6 "In2.Cu" signal "IN1")
		(8 "In3.Cu" signal "GND1")
		(10 "In4.Cu" signal "IN2")
		(12 "In5.Cu" signal "GND2")
		(14 "In6.Cu" signal "IN3")
		(16 "In7.Cu" signal "GND3")
		(18 "In8.Cu" signal "VCC")
		(20 "In9.Cu" signal "VCC1")
		(22 "In10.Cu" signal "GND4")
		(24 "In11.Cu" signal "IN4")
		(26 "In12.Cu" signal "GND5")
		(28 "In13.Cu" signal "IN5")
		(30 "In14.Cu" signal "GND6")
		(32 "In15.Cu" signal "IN6")
		(34 "In16.Cu" signal "GND7")
		(2 "B.Cu" signal "BOTTOM")
		(9 "F.Adhes" user "F.Adhesive")
		(11 "B.Adhes" user "B.Adhesive")
		(13 "F.Paste" user "Package Geometry/Pastemask Top")
		(15 "B.Paste" user "Package Geometry/Pastemask Bottom")
		(5 "F.SilkS" user "Ref Des/Silkscreen Top")
		(7 "B.SilkS" user "Ref Des/Silkscreen Bottom")
		(1 "F.Mask" user "Board Geometry/Soldermask Top")
		(3 "B.Mask" user "Board Geometry/Soldermask Bottom")
		(17 "Dwgs.User" user "User.Drawings")
		(19 "Cmts.User" user "User.Comments")
		(21 "Eco1.User" user "User.Eco1")
		(23 "Eco2.User" user "User.Eco2")
		(25 "Edge.Cuts" user "Board Geometry/Outline")
		(27 "Margin" user)
		(31 "F.CrtYd" user "Package Geometry/Place Bound Top")
		(29 "B.CrtYd" user "Package Geometry/Place Bound Bottom")
		(35 "F.Fab" user "Ref Des/Assembly Top")
		(33 "B.Fab" user "Ref Des/Assembly Bottom")
	)
	(footprint ""
		(layer "F.Cu")
		(at 438.996074 -360.606848)
		(property "Reference" "PL24"
			(at -2.3876 -2.969768 0)
			(unlocked yes)
			(layer "F.SilkS")
			(effects
				(font
					(size 0.7874 0.5842)
					(thickness 0.1524)
				)
				(justify left)
			)
		)
		(property "Value" ""
			(at 0 0 0)
			(layer "F.Fab")
			(effects
				(font
					(size 1.27 1.27)
				)
			)
		)
		(duplicate_pad_numbers_are_jumpers no)
		(fp_line
			(start -2.249932 -2.249932)
			(end 2.249932 -2.249932)
			(stroke
				(width 0.1524)
				(type default)
			)
			(layer "F.SilkS")
		)
		(fp_line
			(start -2.249932 -1.3843)
			(end -2.249932 -2.249932)
			(stroke
				(width 0.1524)
				(type default)
			)
			(layer "F.SilkS")
		)
		(fp_line
			(start -2.249932 2.249932)
			(end -2.249932 1.3843)
			(stroke
				(width 0.1524)
				(type default)
			)
			(layer "F.SilkS")
		)
		(fp_line
			(start 2.249932 -2.249932)
			(end 2.249932 -1.3843)
			(stroke
				(width 0.1524)
				(type default)
			)
			(layer "F.SilkS")
		)
		(fp_line
			(start 2.249932 1.3843)
			(end 2.249932 2.249932)
			(stroke
				(width 0.1524)
				(type default)
			)
			(layer "F.SilkS")
		)
		(fp_line
			(start 2.249932 2.249932)
			(end -2.249932 2.249932)
			(stroke
				(width 0.1524)
				(type default)
			)
			(layer "F.SilkS")
		)
		(fp_line
			(start -2.249932 -2.249932)
			(end 2.249932 -2.249932)
			(stroke
				(width 0.1)
				(type default)
			)
			(layer "F.Fab")
		)
		(fp_line
			(start -2.249932 2.249932)
			(end -2.249932 -2.249932)
			(stroke
				(width 0.1)
				(type default)
			)
			(layer "F.Fab")
		)
		(fp_line
			(start 2.249932 -2.249932)
			(end 2.249932 2.249932)
			(stroke
				(width 0.1)
				(type default)
			)
			(layer "F.Fab")
		)
		(fp_line
			(start 2.249932 2.249932)
			(end -2.249932 2.249932)
			(stroke
				(width 0.1)
				(type default)
			)
			(layer "F.Fab")
		)
		(pad "1" smd rect
			(at -1.82499 0)
			(size 1.0668 2.5146)
			(layers "F.Cu" "F.Mask" "F.Paste")
			(net "SW_P12V_AUX_PVDD11_S3_P0_FLT")
		)
		(pad "2" smd rect
			(at 1.82499 0)
			(size 1.0668 2.5146)
			(layers "F.Cu" "F.Mask" "F.Paste")
			(net "P12V_AUX")
		)
	)
	(footprint ""
		(layer "F.Cu")
		(at 402.487638 -168.510966 90)
		(property "Reference" "PC584_2"
			(at 0 0 90)
			(layer "F.SilkS")
			(hide yes)
			(effects
				(font
					(size 1.27 1.27)
				)
			)
		)
		(property "Value" ""
			(at 0 0 90)
			(layer "F.Fab")
			(effects
				(font
					(size 1.27 1.27)
				)
			)
		)
		(duplicate_pad_numbers_are_jumpers no)
		(fp_line
			(start 0.7874 -0.4064)
			(end 0.7874 0.4064)
			(stroke
				(width 0.1524)
				(type default)
			)
			(layer "F.SilkS")
		)
		(fp_line
			(start -0.7874 -0.4064)
			(end 0.7874 -0.4064)
			(stroke
				(width 0.1524)
				(type default)
			)
			(layer "F.SilkS")
		)
		(fp_line
			(start 0.7874 0.4064)
			(end -0.7874 0.4064)
			(stroke
				(width 0.1524)
				(type default)
			)
			(layer "F.SilkS")
		)
		(fp_line
			(start -0.7874 0.4064)
			(end -0.7874 -0.4064)
			(stroke
				(width 0.1524)
				(type default)
			)
			(layer "F.SilkS")
		)
		(fp_line
			(start -0.12065 -0.305054)
			(end -0.12065 -0.2794)
			(stroke
				(width 0.1)
				(type default)
			)
			(layer "F.Fab")
		)
		(fp_line
			(start -0.67945 -0.305054)
			(end -0.12065 -0.305054)
			(stroke
				(width 0.1)
				(type default)
			)
			(layer "F.Fab")
		)
		(fp_line
			(start 0.67945 -0.3048)
			(end 0.67945 0.3048)
			(stroke
				(width 0.1)
				(type default)
			)
			(layer "F.Fab")
		)
		(fp_line
			(start 0.12065 -0.3048)
			(end 0.67945 -0.3048)
			(stroke
				(width 0.1)
				(type default)
			)
			(layer "F.Fab")
		)
		(fp_line
			(start 0.12065 -0.2794)
			(end 0.12065 -0.3048)
			(stroke
				(width 0.1)
				(type default)
			)
			(layer "F.Fab")
		)
		(fp_line
			(start -0.12065 -0.2794)
			(end 0.12065 -0.2794)
			(stroke
				(width 0.1)
				(type default)
			)
			(layer "F.Fab")
		)
		(fp_line
			(start 0.120396 0.2794)
			(end -0.12065 0.2794)
			(stroke
				(width 0.1)
				(type default)
			)
			(layer "F.Fab")
		)
		(fp_line
			(start -0.12065 0.2794)
			(end -0.12065 0.3048)
			(stroke
				(width 0.1)
				(type default)
			)
			(layer "F.Fab")
		)
		(fp_line
			(start 0.67945 0.3048)
			(end 0.120396 0.3048)
			(stroke
				(width 0.1)
				(type default)
			)
			(layer "F.Fab")
		)
		(fp_line
			(start 0.120396 0.3048)
			(end 0.120396 0.2794)
			(stroke
				(width 0.1)
				(type default)
			)
			(layer "F.Fab")
		)
		(fp_line
			(start -0.12065 0.3048)
			(end -0.67945 0.3048)
			(stroke
				(width 0.1)
				(type default)
			)
			(layer "F.Fab")
		)
		(fp_line
			(start -0.67945 0.3048)
			(end -0.67945 -0.305054)
			(stroke
				(width 0.1)
				(type default)
			)
			(layer "F.Fab")
		)
		(pad "1" smd circle
			(at -0.40005 0 90)
			(size 0 0)
			(layers "F.Cu" "F.Mask" "F.Paste")
			(net "SW_P12V_AUX_PVDDCR_SOC_P0_FLT")
		)
		(pad "2" smd circle
			(at 0.40005 0 90)
			(size 0 0)
			(layers "F.Cu" "F.Mask" "F.Paste")
			(net "GND")
		)
	)
	(footprint ""
		(layer "F.Cu")
		(at 259.834126 -96.206056 180)
		(property "Reference" "R1633"
			(at 0 0 180)
			(layer "F.SilkS")
			(hide yes)
			(effects
				(font
					(size 1.27 1.27)
				)
			)
		)
		(property "Value" ""
			(at 0 0 180)
			(layer "F.Fab")
			(effects
				(font
					(size 1.27 1.27)
				)
			)
		)
		(duplicate_pad_numbers_are_jumpers no)
		(fp_line
			(start 0.7874 0.4064)
			(end -0.7874 0.4064)
			(stroke
				(width 0.1524)
				(type default)
			)
			(layer "F.SilkS")
		)
		(fp_line
			(start 0.7874 -0.4064)
			(end 0.7874 0.4064)
			(stroke
				(width 0.1524)
				(type default)
			)
			(layer "F.SilkS")
		)
		(fp_line
			(start -0.7874 0.4064)
			(end -0.7874 -0.4064)
			(stroke
				(width 0.1524)
				(type default)
			)
			(layer "F.SilkS")
		)
		(fp_line
			(start -0.7874 -0.4064)
			(end 0.7874 -0.4064)
			(stroke
				(width 0.1524)
				(type default)
			)
			(layer "F.SilkS")
		)
		(fp_line
			(start 0.67945 0.3048)
			(end 0.120396 0.3048)
			(stroke
				(width 0.1)
				(type default)
			)
			(layer "F.Fab")
		)
		(fp_line
			(start 0.67945 -0.3048)
			(end 0.67945 0.3048)
			(stroke
				(width 0.1)
				(type default)
			)
			(layer "F.Fab")
		)
		(fp_line
			(start 0.12065 -0.2794)
			(end 0.12065 -0.3048)
			(stroke
				(width 0.1)
				(type default)
			)
			(layer "F.Fab")
		)
		(fp_line
			(start 0.12065 -0.3048)
			(end 0.67945 -0.3048)
			(stroke
				(width 0.1)
				(type default)
			)
			(layer "F.Fab")
		)
		(fp_line
			(start 0.120396 0.3048)
			(end 0.120396 0.2794)
			(stroke
				(width 0.1)
				(type default)
			)
			(layer "F.Fab")
		)
		(fp_line
			(start 0.120396 0.2794)
			(end -0.12065 0.2794)
			(stroke
				(width 0.1)
				(type default)
			)
			(layer "F.Fab")
		)
		(fp_line
			(start -0.12065 0.3048)
			(end -0.67945 0.3048)
			(stroke
				(width 0.1)
				(type default)
			)
			(layer "F.Fab")
		)
		(fp_line
			(start -0.12065 0.2794)
			(end -0.12065 0.3048)
			(stroke
				(width 0.1)
				(type default)
			)
			(layer "F.Fab")
		)
		(fp_line
			(start -0.12065 -0.2794)
			(end 0.12065 -0.2794)
			(stroke
				(width 0.1)
				(type default)
			)
			(layer "F.Fab")
		)
		(fp_line
			(start -0.12065 -0.305054)
			(end -0.12065 -0.2794)
			(stroke
				(width 0.1)
				(type default)
			)
			(layer "F.Fab")
		)
		(fp_line
			(start -0.67945 0.3048)
			(end -0.67945 -0.305054)
			(stroke
				(width 0.1)
				(type default)
			)
			(layer "F.Fab")
		)
		(fp_line
			(start -0.67945 -0.305054)
			(end -0.12065 -0.305054)
			(stroke
				(width 0.1)
				(type default)
			)
			(layer "F.Fab")
		)
		(pad "1" smd circle
			(at -0.40005 0 180)
			(size 0 0)
			(layers "F.Cu" "F.Mask" "F.Paste")
			(net "JTAG_TCK_R")
		)
		(pad "2" smd circle
			(at 0.40005 0 180)
			(size 0 0)
			(layers "F.Cu" "F.Mask" "F.Paste")
			(net "JTAG_TCK")
		)
	)
)
